# T6G (Grand Teton) — schematic netlist excerpt (pin names and nets, part order shuffled) for the footprints in the layout excerpt that follows; sources: Cadence DE-HDL packaged netlist, KiCad conversion of 04192023_DAF0TMB3IC0_F0TG_MB_C_brd_V02_OCP.brd

PC619_IOP1_3  Q_CAP  2.2UF 10V 10% X6S  pkg C0402  page 223 : A = PVDDCR_CPU1_P1_PVCC ; B = GND
C1508  Q_CAP  0.1UF 16V 10% X7R  pkg C0402  page 172 : A = PVDD18_S5_P0 ; B = GND

(kicad_pcb
	(version 20260206)
	(generator "pcbnew")
	(generator_version "10.0")
	(general
		(thickness 1.6)
		(legacy_teardrops no)
	)
	(paper "A4")
	(title_block
		(title "04192023_DAF0TMB3IC0_F0TG_MB_C_brd_V02_OCP.brd")
		(comment 1 "Grand Teton / footprints 1664-1665 of 8354")
	)
	(layers
		(0 "F.Cu" signal "TOP")
		(4 "In1.Cu" signal "GND")
		(6 "In2.Cu" signal "IN1")
		(8 "In3.Cu" signal "GND1")
		(10 "In4.Cu" signal "IN2")
		(12 "In5.Cu" signal "GND2")
		(14 "In6.Cu" signal "IN3")
		(16 "In7.Cu" signal "GND3")
		(18 "In8.Cu" signal "VCC")
		(20 "In9.Cu" signal "VCC1")
		(22 "In10.Cu" signal "GND4")
		(24 "In11.Cu" signal "IN4")
		(26 "In12.Cu" signal "GND5")
		(28 "In13.Cu" signal "IN5")
		(30 "In14.Cu" signal "GND6")
		(32 "In15.Cu" signal "IN6")
		(34 "In16.Cu" signal "GND7")
		(2 "B.Cu" signal "BOTTOM")
		(9 "F.Adhes" user "F.Adhesive")
		(11 "B.Adhes" user "B.Adhesive")
		(13 "F.Paste" user "Package Geometry/Pastemask Top")
		(15 "B.Paste" user "Package Geometry/Pastemask Bottom")
		(5 "F.SilkS" user "Ref Des/Silkscreen Top")
		(7 "B.SilkS" user "Ref Des/Silkscreen Bottom")
		(1 "F.Mask" user "Board Geometry/Soldermask Top")
		(3 "B.Mask" user "Board Geometry/Soldermask Bottom")
		(17 "Dwgs.User" user "User.Drawings")
		(19 "Cmts.User" user "User.Comments")
		(21 "Eco1.User" user "User.Eco1")
		(23 "Eco2.User" user "User.Eco2")
		(25 "Edge.Cuts" user "Board Geometry/Outline")
		(27 "Margin" user)
		(31 "F.CrtYd" user "Package Geometry/Place Bound Top")
		(29 "B.CrtYd" user "Package Geometry/Place Bound Bottom")
		(35 "F.Fab" user "Ref Des/Assembly Top")
		(33 "B.Fab" user "Ref Des/Assembly Bottom")
	)
	(footprint ""
		(layer "F.Cu")
		(at 265.49223 -103.272844 180)
		(property "Reference" "C1508"
			(at 0 0 180)
			(layer "F.SilkS")
			(hide yes)
			(effects
				(font
					(size 1.27 1.27)
				)
			)
		)
		(property "Value" ""
			(at 0 0 180)
			(layer "F.Fab")
			(effects
				(font
					(size 1.27 1.27)
				)
			)
		)
		(duplicate_pad_numbers_are_jumpers no)
		(fp_line
			(start 0.7874 0.4064)
			(end -0.7874 0.4064)
			(stroke
				(width 0.1524)
				(type default)
			)
			(layer "F.SilkS")
		)
		(fp_line
			(start 0.7874 -0.4064)
			(end 0.7874 0.4064)
			(stroke
				(width 0.1524)
				(type default)
			)
			(layer "F.SilkS")
		)
		(fp_line
			(start -0.7874 0.4064)
			(end -0.7874 -0.4064)
			(stroke
				(width 0.1524)
				(type default)
			)
			(layer "F.SilkS")
		)
		(fp_line
			(start -0.7874 -0.4064)
			(end 0.7874 -0.4064)
			(stroke
				(width 0.1524)
				(type default)
			)
			(layer "F.SilkS")
		)
		(fp_line
			(start 0.67945 0.3048)
			(end 0.120396 0.3048)
			(stroke
				(width 0.1)
				(type default)
			)
			(layer "F.Fab")
		)
		(fp_line
			(start 0.67945 -0.3048)
			(end 0.67945 0.3048)
			(stroke
				(width 0.1)
				(type default)
			)
			(layer "F.Fab")
		)
		(fp_line
			(start 0.12065 -0.2794)
			(end 0.12065 -0.3048)
			(stroke
				(width 0.1)
				(type default)
			)
			(layer "F.Fab")
		)
		(fp_line
			(start 0.12065 -0.3048)
			(end 0.67945 -0.3048)
			(stroke
				(width 0.1)
				(type default)
			)
			(layer "F.Fab")
		)
		(fp_line
			(start 0.120396 0.3048)
			(end 0.120396 0.2794)
			(stroke
				(width 0.1)
				(type default)
			)
			(layer "F.Fab")
		)
		(fp_line
			(start 0.120396 0.2794)
			(end -0.12065 0.2794)
			(stroke
				(width 0.1)
				(type default)
			)
			(layer "F.Fab")
		)
		(fp_line
			(start -0.12065 0.3048)
			(end -0.67945 0.3048)
			(stroke
				(width 0.1)
				(type default)
			)
			(layer "F.Fab")
		)
		(fp_line
			(start -0.12065 0.2794)
			(end -0.12065 0.3048)
			(stroke
				(width 0.1)
				(type default)
			)
			(layer "F.Fab")
		)
		(fp_line
			(start -0.12065 -0.2794)
			(end 0.12065 -0.2794)
			(stroke
				(width 0.1)
				(type default)
			)
			(layer "F.Fab")
		)
		(fp_line
			(start -0.12065 -0.305054)
			(end -0.12065 -0.2794)
			(stroke
				(width 0.1)
				(type default)
			)
			(layer "F.Fab")
		)
		(fp_line
			(start -0.67945 0.3048)
			(end -0.67945 -0.305054)
			(stroke
				(width 0.1)
				(type default)
			)
			(layer "F.Fab")
		)
		(fp_line
			(start -0.67945 -0.305054)
			(end -0.12065 -0.305054)
			(stroke
				(width 0.1)
				(type default)
			)
			(layer "F.Fab")
		)
		(pad "1" smd circle
			(at -0.40005 0 180)
			(size 0 0)
			(layers "F.Cu" "F.Mask" "F.Paste")
			(net "PVDD18_S5_P0")
		)
		(pad "2" smd circle
			(at 0.40005 0 180)
			(size 0 0)
			(layers "F.Cu" "F.Mask" "F.Paste")
			(net "GND")
		)
	)
	(footprint ""
		(layer "F.Cu")
		(at 33.198054 -346.719398 -90)
		(property "Reference" "PC619_IOP1_3"
			(at 0 0 270)
			(layer "F.SilkS")
			(hide yes)
			(effects
				(font
					(size 1.27 1.27)
				)
			)
		)
		(property "Value" ""
			(at 0 0 270)
			(layer "F.Fab")
			(effects
				(font
					(size 1.27 1.27)
				)
			)
		)
		(duplicate_pad_numbers_are_jumpers no)
		(fp_line
			(start -0.7874 0.4064)
			(end -0.7874 -0.4064)
			(stroke
				(width 0.1524)
				(type default)
			)
			(layer "F.SilkS")
		)
		(fp_line
			(start 0.7874 0.4064)
			(end -0.7874 0.4064)
			(stroke
				(width 0.1524)
				(type default)
			)
			(layer "F.SilkS")
		)
		(fp_line
			(start -0.7874 -0.4064)
			(end 0.7874 -0.4064)
			(stroke
				(width 0.1524)
				(type default)
			)
			(layer "F.SilkS")
		)
		(fp_line
			(start 0.7874 -0.4064)
			(end 0.7874 0.4064)
			(stroke
				(width 0.1524)
				(type default)
			)
			(layer "F.SilkS")
		)
		(fp_line
			(start -0.67945 0.3048)
			(end -0.67945 -0.305054)
			(stroke
				(width 0.1)
				(type default)
			)
			(layer "F.Fab")
		)
		(fp_line
			(start -0.12065 0.3048)
			(end -0.67945 0.3048)
			(stroke
				(width 0.1)
				(type default)
			)
			(layer "F.Fab")
		)
		(fp_line
			(start 0.120396 0.3048)
			(end 0.120396 0.2794)
			(stroke
				(width 0.1)
				(type default)
			)
			(layer "F.Fab")
		)
		(fp_line
			(start 0.67945 0.3048)
			(end 0.120396 0.3048)
			(stroke
				(width 0.1)
				(type default)
			)
			(layer "F.Fab")
		)
		(fp_line
			(start -0.12065 0.2794)
			(end -0.12065 0.3048)
			(stroke
				(width 0.1)
				(type default)
			)
			(layer "F.Fab")
		)
		(fp_line
			(start 0.120396 0.2794)
			(end -0.12065 0.2794)
			(stroke
				(width 0.1)
				(type default)
			)
			(layer "F.Fab")
		)
		(fp_line
			(start -0.12065 -0.2794)
			(end 0.12065 -0.2794)
			(stroke
				(width 0.1)
				(type default)
			)
			(layer "F.Fab")
		)
		(fp_line
			(start 0.12065 -0.2794)
			(end 0.12065 -0.3048)
			(stroke
				(width 0.1)
				(type default)
			)
			(layer "F.Fab")
		)
		(fp_line
			(start 0.12065 -0.3048)
			(end 0.67945 -0.3048)
			(stroke
				(width 0.1)
				(type default)
			)
			(layer "F.Fab")
		)
		(fp_line
			(start 0.67945 -0.3048)
			(end 0.67945 0.3048)
			(stroke
				(width 0.1)
				(type default)
			)
			(layer "F.Fab")
		)
		(fp_line
			(start -0.67945 -0.305054)
			(end -0.12065 -0.305054)
			(stroke
				(width 0.1)
				(type default)
			)
			(layer "F.Fab")
		)
		(fp_line
			(start -0.12065 -0.305054)
			(end -0.12065 -0.2794)
			(stroke
				(width 0.1)
				(type default)
			)
			(layer "F.Fab")
		)
		(pad "1" smd circle
			(at -0.40005 0 270)
			(size 0 0)
			(layers "F.Cu" "F.Mask" "F.Paste")
			(net "PVDDCR_CPU1_P1_PVCC")
		)
		(pad "2" smd circle
			(at 0.40005 0 270)
			(size 0 0)
			(layers "F.Cu" "F.Mask" "F.Paste")
			(net "GND")
		)
	)
)
